(kicad_pcb
	(version 20260206)
	(generator "pcbnew")
	(generator_version "10.0")
	(general
		(thickness 1.6)
		(legacy_teardrops no)
	)
	(paper "A4")
	(title_block
		(title "pdpb — Lightning_PDPB_BRD.brd")
		(comment 1 "Lightning (Wiwynn / Facebook NVMe JBOF) / footprints 137-143 of 1140")
	)
	(layers
		(0 "F.Cu" signal "TOP")
		(4 "In1.Cu" signal "L2GND")
		(6 "In2.Cu" signal "L3")
		(8 "In3.Cu" signal "L4VCC")
		(10 "In4.Cu" signal "L5VCC")
		(12 "In5.Cu" signal "L6")
		(14 "In6.Cu" signal "L7GND")
		(2 "B.Cu" signal "BOTTOM")
		(9 "F.Adhes" user "F.Adhesive")
		(11 "B.Adhes" user "B.Adhesive")
		(13 "F.Paste" user "Package Geometry/Pastemask Top")
		(15 "B.Paste" user "Package Geometry/Pastemask Bottom")
		(5 "F.SilkS" user "Ref Des/Silkscreen Top")
		(7 "B.SilkS" user "Ref Des/Silkscreen Bottom")
		(1 "F.Mask" user "Board Geometry/Soldermask Top")
		(3 "B.Mask" user "Board Geometry/Soldermask Bottom")
		(17 "Dwgs.User" user "User.Drawings")
		(19 "Cmts.User" user "User.Comments")
		(21 "Eco1.User" user "User.Eco1")
		(23 "Eco2.User" user "User.Eco2")
		(25 "Edge.Cuts" user "Board Geometry/Outline")
		(27 "Margin" user)
		(31 "F.CrtYd" user "Package Geometry/Place Bound Top")
		(29 "B.CrtYd" user "Package Geometry/Place Bound Bottom")
		(35 "F.Fab" user "Ref Des/Assembly Top")
		(33 "B.Fab" user "Ref Des/Assembly Bottom")
	)
	(footprint ""
		(layer "F.Cu")
		(at 90.043 -86.614 -90)
		(property "Reference" "R9507"
			(at 0 0 270)
			(layer "F.SilkS")
			(hide yes)
			(effects
				(font
					(size 1.27 1.27)
				)
			)
		)
		(property "Value" "4K7R2J-2-GP"
			(at 0.064008 -3.993896 270)
			(unlocked yes)
			(layer "F.Fab")
			(hide yes)
			(effects
				(font
					(size 1.016 1.016)
					(thickness 0.1524)
				)
			)
		)
		(property "Device Type" "R402H16"
			(at 0.064008 -5.517896 270)
			(unlocked yes)
			(layer "F.Fab")
			(hide yes)
			(effects
				(font
					(size 1.016 1.016)
					(thickness 0.1524)
				)
			)
		)
		(duplicate_pad_numbers_are_jumpers no)
		(fp_line
			(start -0.508 -0.9398)
			(end -0.508 0.9398)
			(stroke
				(width 0.1524)
				(type default)
			)
			(layer "F.SilkS")
		)
		(fp_line
			(start 0.508 -0.9398)
			(end -0.508 -0.9398)
			(stroke
				(width 0.1524)
				(type default)
			)
			(layer "F.SilkS")
		)
		(fp_rect
			(start -0.508 0.9398)
			(end 0.508 -0.9398)
			(stroke
				(width 0)
				(type default)
			)
			(fill no)
			(layer "F.CrtYd")
		)
		(fp_rect
			(start -0.508 0.9398)
			(end 0.508 -0.9398)
			(stroke
				(width 0)
				(type default)
			)
			(fill no)
			(layer "F.Fab")
		)
		(pad "1" smd custom
			(at 0 -0.4445 270)
			(size 0.1397 0.1397)
			(layers "F.Cu" "F.Mask" "F.Paste")
			(net "P3V3")
			(options
				(clearance outline)
				(anchor circle)
			)
			(primitives
				(gr_poly
					(pts
						(arc
							(start -0.1778 -0.2794)
							(mid -0.249642 -0.249642)
							(end -0.2794 -0.1778)
						)
						(arc
							(start -0.2794 0.1778)
							(mid -0.249642 0.249642)
							(end -0.1778 0.2794)
						)
						(arc
							(start 0.1778 0.2794)
							(mid 0.249642 0.249642)
							(end 0.2794 0.1778)
						)
						(arc
							(start 0.2794 -0.1778)
							(mid 0.249642 -0.249642)
							(end 0.1778 -0.2794)
						)
					)
					(width 0)
					(fill yes)
				)
			)
		)
		(pad "2" smd custom
			(at 0 0.4445 270)
			(size 0.1397 0.1397)
			(layers "F.Cu" "F.Mask" "F.Paste")
			(net "SSD9_CLK0_OE_N")
			(options
				(clearance outline)
				(anchor circle)
			)
			(primitives
				(gr_poly
					(pts
						(arc
							(start -0.1778 -0.2794)
							(mid -0.249642 -0.249642)
							(end -0.2794 -0.1778)
						)
						(arc
							(start -0.2794 0.1778)
							(mid -0.249642 0.249642)
							(end -0.1778 0.2794)
						)
						(arc
							(start 0.1778 0.2794)
							(mid 0.249642 0.249642)
							(end 0.2794 0.1778)
						)
						(arc
							(start 0.2794 -0.1778)
							(mid 0.249642 -0.249642)
							(end 0.1778 -0.2794)
						)
					)
					(width 0)
					(fill yes)
				)
			)
		)
	)
	(footprint ""
		(layer "F.Cu")
		(at 102.235 -216.027 -90)
		(property "Reference" "R9584"
			(at 0 0 270)
			(layer "F.SilkS")
			(hide yes)
			(effects
				(font
					(size 1.27 1.27)
				)
			)
		)
		(property "Value" "0R5J-L1-GP"
			(at 0 -8.9535 270)
			(unlocked yes)
			(layer "F.Fab")
			(hide yes)
			(effects
				(font
					(size 1.27 1.016)
					(thickness 0.1524)
				)
			)
		)
		(property "Device Type" "R805H24"
			(at 0 -10.6299 270)
			(unlocked yes)
			(layer "F.Fab")
			(hide yes)
			(effects
				(font
					(size 1.27 1.016)
					(thickness 0.1524)
				)
			)
		)
		(duplicate_pad_numbers_are_jumpers no)
		(fp_line
			(start -0.889 1.7018)
			(end 0.889 1.7018)
			(stroke
				(width 0.1524)
				(type default)
			)
			(layer "F.SilkS")
		)
		(fp_line
			(start 0.889 1.7018)
			(end 0.889 -0.508)
			(stroke
				(width 0.1524)
				(type default)
			)
			(layer "F.SilkS")
		)
		(fp_line
			(start -0.889 0.0762)
			(end -0.889 1.7018)
			(stroke
				(width 0.1524)
				(type default)
			)
			(layer "F.SilkS")
		)
		(fp_line
			(start -0.889 -1.7018)
			(end -0.889 0.2794)
			(stroke
				(width 0.1524)
				(type default)
			)
			(layer "F.SilkS")
		)
		(fp_line
			(start 0.889 -1.7018)
			(end 0.889 -0.381)
			(stroke
				(width 0.1524)
				(type default)
			)
			(layer "F.SilkS")
		)
		(fp_line
			(start 0.889 -1.7018)
			(end -0.889 -1.7018)
			(stroke
				(width 0.1524)
				(type default)
			)
			(layer "F.SilkS")
		)
		(fp_poly
			(pts
				(xy 0.9652 -1.778) (xy 0.9652 1.778) (xy -0.9652 1.778) (xy -0.9652 -1.778)
			)
			(stroke
				(width 0)
				(type default)
			)
			(fill no)
			(layer "F.CrtYd")
		)
		(fp_rect
			(start -0.9652 1.778)
			(end 0.9652 -1.778)
			(stroke
				(width 0)
				(type default)
			)
			(fill no)
			(layer "F.Fab")
		)
		(pad "1" smd rect
			(at 0 -0.9652 270)
			(size 1.397 1.143)
			(layers "F.Cu" "F.Mask" "F.Paste")
			(net "P3V3")
		)
		(pad "2" smd rect
			(at 0 0.9652 270)
			(size 1.397 1.143)
			(layers "F.Cu" "F.Mask" "F.Paste")
			(net "VDD_IO_3")
		)
	)
	(footprint ""
		(layer "F.Cu")
		(at 92.837 -17.399 -90)
		(property "Reference" "R389"
			(at 0 0 270)
			(layer "F.SilkS")
			(hide yes)
			(effects
				(font
					(size 1.27 1.27)
				)
			)
		)
		(property "Value" "2KR2F-3-GP"
			(at 0.064008 -3.993896 270)
			(unlocked yes)
			(layer "F.Fab")
			(hide yes)
			(effects
				(font
					(size 1.016 1.016)
					(thickness 0.1524)
				)
			)
		)
		(property "Device Type" "R402H16"
			(at 0.064008 -5.517896 270)
			(unlocked yes)
			(layer "F.Fab")
			(hide yes)
			(effects
				(font
					(size 1.016 1.016)
					(thickness 0.1524)
				)
			)
		)
		(duplicate_pad_numbers_are_jumpers no)
		(fp_line
			(start -0.508 -0.9398)
			(end -0.508 0.9398)
			(stroke
				(width 0.1524)
				(type default)
			)
			(layer "F.SilkS")
		)
		(fp_line
			(start 0.508 -0.9398)
			(end -0.508 -0.9398)
			(stroke
				(width 0.1524)
				(type default)
			)
			(layer "F.SilkS")
		)
		(fp_rect
			(start -0.508 0.9398)
			(end 0.508 -0.9398)
			(stroke
				(width 0)
				(type default)
			)
			(fill no)
			(layer "F.CrtYd")
		)
		(fp_rect
			(start -0.508 0.9398)
			(end 0.508 -0.9398)
			(stroke
				(width 0)
				(type default)
			)
			(fill no)
			(layer "F.Fab")
		)
		(pad "1" smd custom
			(at 0 -0.4445 270)
			(size 0.1397 0.1397)
			(layers "F.Cu" "F.Mask" "F.Paste")
			(net "P12V_SENSE")
			(options
				(clearance outline)
				(anchor circle)
			)
			(primitives
				(gr_poly
					(pts
						(arc
							(start -0.1778 -0.2794)
							(mid -0.249642 -0.249642)
							(end -0.2794 -0.1778)
						)
						(arc
							(start -0.2794 0.1778)
							(mid -0.249642 0.249642)
							(end -0.1778 0.2794)
						)
						(arc
							(start 0.1778 0.2794)
							(mid 0.249642 0.249642)
							(end 0.2794 0.1778)
						)
						(arc
							(start 0.2794 -0.1778)
							(mid 0.249642 -0.249642)
							(end 0.1778 -0.2794)
						)
					)
					(width 0)
					(fill yes)
				)
			)
		)
		(pad "2" smd custom
			(at 0 0.4445 270)
			(size 0.1397 0.1397)
			(layers "F.Cu" "F.Mask" "F.Paste")
			(net "GND")
			(options
				(clearance outline)
				(anchor circle)
			)
			(primitives
				(gr_poly
					(pts
						(arc
							(start -0.1778 -0.2794)
							(mid -0.249642 -0.249642)
							(end -0.2794 -0.1778)
						)
						(arc
							(start -0.2794 0.1778)
							(mid -0.249642 0.249642)
							(end -0.1778 0.2794)
						)
						(arc
							(start 0.1778 0.2794)
							(mid 0.249642 0.249642)
							(end 0.2794 0.1778)
						)
						(arc
							(start 0.2794 -0.1778)
							(mid 0.249642 -0.249642)
							(end 0.1778 -0.2794)
						)
					)
					(width 0)
					(fill yes)
				)
			)
		)
	)
	(footprint ""
		(layer "F.Cu")
		(at 84.074 -146.9644 -90)
		(property "Reference" "R372"
			(at 0 0 270)
			(layer "F.SilkS")
			(hide yes)
			(effects
				(font
					(size 1.27 1.27)
				)
			)
		)
		(property "Value" "4K7R2J-2-GP"
			(at 0.064008 -3.993896 270)
			(unlocked yes)
			(layer "F.Fab")
			(hide yes)
			(effects
				(font
					(size 1.016 1.016)
					(thickness 0.1524)
				)
			)
		)
		(property "Device Type" "R402H16"
			(at 0.064008 -5.517896 270)
			(unlocked yes)
			(layer "F.Fab")
			(hide yes)
			(effects
				(font
					(size 1.016 1.016)
					(thickness 0.1524)
				)
			)
		)
		(duplicate_pad_numbers_are_jumpers no)
		(fp_line
			(start -0.508 -0.9398)
			(end -0.508 0.9398)
			(stroke
				(width 0.1524)
				(type default)
			)
			(layer "F.SilkS")
		)
		(fp_line
			(start 0.508 -0.9398)
			(end -0.508 -0.9398)
			(stroke
				(width 0.1524)
				(type default)
			)
			(layer "F.SilkS")
		)
		(fp_rect
			(start -0.508 0.9398)
			(end 0.508 -0.9398)
			(stroke
				(width 0)
				(type default)
			)
			(fill no)
			(layer "F.CrtYd")
		)
		(fp_rect
			(start -0.508 0.9398)
			(end 0.508 -0.9398)
			(stroke
				(width 0)
				(type default)
			)
			(fill no)
			(layer "F.Fab")
		)
		(pad "1" smd custom
			(at 0 -0.4445 270)
			(size 0.1397 0.1397)
			(layers "F.Cu" "F.Mask" "F.Paste")
			(net "P3V3")
			(options
				(clearance outline)
				(anchor circle)
			)
			(primitives
				(gr_poly
					(pts
						(arc
							(start -0.1778 -0.2794)
							(mid -0.249642 -0.249642)
							(end -0.2794 -0.1778)
						)
						(arc
							(start -0.2794 0.1778)
							(mid -0.249642 0.249642)
							(end -0.1778 0.2794)
						)
						(arc
							(start 0.1778 0.2794)
							(mid 0.249642 0.249642)
							(end 0.2794 0.1778)
						)
						(arc
							(start 0.2794 -0.1778)
							(mid 0.249642 -0.249642)
							(end 0.1778 -0.2794)
						)
					)
					(width 0)
					(fill yes)
				)
			)
		)
		(pad "2" smd custom
			(at 0 0.4445 270)
			(size 0.1397 0.1397)
			(layers "F.Cu" "F.Mask" "F.Paste")
			(net "BMC_I2C_SDA_BUF_8")
			(options
				(clearance outline)
				(anchor circle)
			)
			(primitives
				(gr_poly
					(pts
						(arc
							(start -0.1778 -0.2794)
							(mid -0.249642 -0.249642)
							(end -0.2794 -0.1778)
						)
						(arc
							(start -0.2794 0.1778)
							(mid -0.249642 0.249642)
							(end -0.1778 0.2794)
						)
						(arc
							(start 0.1778 0.2794)
							(mid 0.249642 0.249642)
							(end 0.2794 0.1778)
						)
						(arc
							(start 0.2794 -0.1778)
							(mid 0.249642 -0.249642)
							(end 0.1778 -0.2794)
						)
					)
					(width 0)
					(fill yes)
				)
			)
		)
	)
	(footprint ""
		(layer "F.Cu")
		(at 218.313 -432.054)
		(property "Reference" "PR9084"
			(at 0 0 0)
			(layer "F.SilkS")
			(hide yes)
			(effects
				(font
					(size 1.27 1.27)
				)
			)
		)
		(property "Value" "2KR2F-3-GP"
			(at 0.064008 -3.993896 0)
			(unlocked yes)
			(layer "F.Fab")
			(hide yes)
			(effects
				(font
					(size 1.016 1.016)
					(thickness 0.1524)
				)
			)
		)
		(property "Device Type" "R402H16"
			(at 0.064008 -5.517896 0)
			(unlocked yes)
			(layer "F.Fab")
			(hide yes)
			(effects
				(font
					(size 1.016 1.016)
					(thickness 0.1524)
				)
			)
		)
		(duplicate_pad_numbers_are_jumpers no)
		(fp_line
			(start -0.508 -0.9398)
			(end -0.508 0.9398)
			(stroke
				(width 0.1524)
				(type default)
			)
			(layer "F.SilkS")
		)
		(fp_line
			(start 0.508 -0.9398)
			(end -0.508 -0.9398)
			(stroke
				(width 0.1524)
				(type default)
			)
			(layer "F.SilkS")
		)
		(fp_rect
			(start -0.508 0.9398)
			(end 0.508 -0.9398)
			(stroke
				(width 0)
				(type default)
			)
			(fill no)
			(layer "F.CrtYd")
		)
		(fp_rect
			(start -0.508 0.9398)
			(end 0.508 -0.9398)
			(stroke
				(width 0)
				(type default)
			)
			(fill no)
			(layer "F.Fab")
		)
		(pad "1" smd custom
			(at 0 -0.4445)
			(size 0.1397 0.1397)
			(layers "F.Cu" "F.Mask" "F.Paste")
			(net "P3V3_SW")
			(options
				(clearance outline)
				(anchor circle)
			)
			(primitives
				(gr_poly
					(pts
						(arc
							(start -0.1778 -0.2794)
							(mid -0.249642 -0.249642)
							(end -0.2794 -0.1778)
						)
						(arc
							(start -0.2794 0.1778)
							(mid -0.249642 0.249642)
							(end -0.1778 0.2794)
						)
						(arc
							(start 0.1778 0.2794)
							(mid 0.249642 0.249642)
							(end 0.2794 0.1778)
						)
						(arc
							(start 0.2794 -0.1778)
							(mid 0.249642 -0.249642)
							(end 0.1778 -0.2794)
						)
					)
					(width 0)
					(fill yes)
				)
			)
		)
		(pad "2" smd custom
			(at 0 0.4445)
			(size 0.1397 0.1397)
			(layers "F.Cu" "F.Mask" "F.Paste")
			(net "P3V3_VFB_R")
			(options
				(clearance outline)
				(anchor circle)
			)
			(primitives
				(gr_poly
					(pts
						(arc
							(start -0.1778 -0.2794)
							(mid -0.249642 -0.249642)
							(end -0.2794 -0.1778)
						)
						(arc
							(start -0.2794 0.1778)
							(mid -0.249642 0.249642)
							(end -0.1778 0.2794)
						)
						(arc
							(start 0.1778 0.2794)
							(mid 0.249642 0.249642)
							(end 0.2794 0.1778)
						)
						(arc
							(start 0.2794 -0.1778)
							(mid 0.249642 -0.249642)
							(end 0.1778 -0.2794)
						)
					)
					(width 0)
					(fill yes)
				)
			)
		)
	)
	(footprint ""
		(layer "F.Cu")
		(at 102.616 -209.296 90)
		(property "Reference" "R9083"
			(at 0 0 90)
			(layer "F.SilkS")
			(hide yes)
			(effects
				(font
					(size 1.27 1.27)
				)
			)
		)
		(property "Value" "27R2F-GP"
			(at 0.064008 -3.993896 90)
			(unlocked yes)
			(layer "F.Fab")
			(hide yes)
			(effects
				(font
					(size 1.016 1.016)
					(thickness 0.1524)
				)
			)
		)
		(property "Device Type" "R402H16"
			(at 0.064008 -5.517896 90)
			(unlocked yes)
			(layer "F.Fab")
			(hide yes)
			(effects
				(font
					(size 1.016 1.016)
					(thickness 0.1524)
				)
			)
		)
		(duplicate_pad_numbers_are_jumpers no)
		(fp_line
			(start 0.508 -0.9398)
			(end -0.508 -0.9398)
			(stroke
				(width 0.1524)
				(type default)
			)
			(layer "F.SilkS")
		)
		(fp_line
			(start -0.508 -0.9398)
			(end -0.508 0.9398)
			(stroke
				(width 0.1524)
				(type default)
			)
			(layer "F.SilkS")
		)
		(fp_rect
			(start -0.508 0.9398)
			(end 0.508 -0.9398)
			(stroke
				(width 0)
				(type default)
			)
			(fill no)
			(layer "F.CrtYd")
		)
		(fp_rect
			(start -0.508 0.9398)
			(end 0.508 -0.9398)
			(stroke
				(width 0)
				(type default)
			)
			(fill no)
			(layer "F.Fab")
		)
		(pad "1" smd custom
			(at 0 -0.4445 90)
			(size 0.1397 0.1397)
			(layers "F.Cu" "F.Mask" "F.Paste")
			(net "PE_CLK_100M_DR3_1_R_N")
			(options
				(clearance outline)
				(anchor circle)
			)
			(primitives
				(gr_poly
					(pts
						(arc
							(start -0.1778 -0.2794)
							(mid -0.249642 -0.249642)
							(end -0.2794 -0.1778)
						)
						(arc
							(start -0.2794 0.1778)
							(mid -0.249642 0.249642)
							(end -0.1778 0.2794)
						)
						(arc
							(start 0.1778 0.2794)
							(mid 0.249642 0.249642)
							(end 0.2794 0.1778)
						)
						(arc
							(start 0.2794 -0.1778)
							(mid 0.249642 -0.249642)
							(end 0.1778 -0.2794)
						)
					)
					(width 0)
					(fill yes)
				)
			)
		)
		(pad "2" smd custom
			(at 0 0.4445 90)
			(size 0.1397 0.1397)
			(layers "F.Cu" "F.Mask" "F.Paste")
			(net "PE_CLK100M_DR3_1_N")
			(options
				(clearance outline)
				(anchor circle)
			)
			(primitives
				(gr_poly
					(pts
						(arc
							(start -0.1778 -0.2794)
							(mid -0.249642 -0.249642)
							(end -0.2794 -0.1778)
						)
						(arc
							(start -0.2794 0.1778)
							(mid -0.249642 0.249642)
							(end -0.1778 0.2794)
						)
						(arc
							(start 0.1778 0.2794)
							(mid 0.249642 0.249642)
							(end 0.2794 0.1778)
						)
						(arc
							(start 0.2794 -0.1778)
							(mid 0.249642 -0.249642)
							(end 0.1778 -0.2794)
						)
					)
					(width 0)
					(fill yes)
				)
			)
		)
	)
	(footprint ""
		(layer "F.Cu")
		(at 209.804 -88.646 -90)
		(property "Reference" "R142"
			(at 0 0 270)
			(layer "F.SilkS")
			(hide yes)
			(effects
				(font
					(size 1.27 1.27)
				)
			)
		)
		(property "Value" "4K7R2J-2-GP"
			(at 0.064008 -3.993896 270)
			(unlocked yes)
			(layer "F.Fab")
			(hide yes)
			(effects
				(font
					(size 1.016 1.016)
					(thickness 0.1524)
				)
			)
		)
		(property "Device Type" "R402H16"
			(at 0.064008 -5.517896 270)
			(unlocked yes)
			(layer "F.Fab")
			(hide yes)
			(effects
				(font
					(size 1.016 1.016)
					(thickness 0.1524)
				)
			)
		)
		(duplicate_pad_numbers_are_jumpers no)
		(fp_line
			(start -0.508 -0.9398)
			(end -0.508 0.9398)
			(stroke
				(width 0.1524)
				(type default)
			)
			(layer "F.SilkS")
		)
		(fp_line
			(start 0.508 -0.9398)
			(end -0.508 -0.9398)
			(stroke
				(width 0.1524)
				(type default)
			)
			(layer "F.SilkS")
		)
		(fp_rect
			(start -0.508 0.9398)
			(end 0.508 -0.9398)
			(stroke
				(width 0)
				(type default)
			)
			(fill no)
			(layer "F.CrtYd")
		)
		(fp_rect
			(start -0.508 0.9398)
			(end 0.508 -0.9398)
			(stroke
				(width 0)
				(type default)
			)
			(fill no)
			(layer "F.Fab")
		)
		(pad "1" smd custom
			(at 0 -0.4445 270)
			(size 0.1397 0.1397)
			(layers "F.Cu" "F.Mask" "F.Paste")
			(net "P12V")
			(options
				(clearance outline)
				(anchor circle)
			)
			(primitives
				(gr_poly
					(pts
						(arc
							(start -0.1778 -0.2794)
							(mid -0.249642 -0.249642)
							(end -0.2794 -0.1778)
						)
						(arc
							(start -0.2794 0.1778)
							(mid -0.249642 0.249642)
							(end -0.1778 0.2794)
						)
						(arc
							(start 0.1778 0.2794)
							(mid 0.249642 0.249642)
							(end 0.2794 0.1778)
						)
						(arc
							(start 0.2794 -0.1778)
							(mid 0.249642 -0.249642)
							(end 0.1778 -0.2794)
						)
					)
					(width 0)
					(fill yes)
				)
			)
		)
		(pad "2" smd custom
			(at 0 0.4445 270)
			(size 0.1397 0.1397)
			(layers "F.Cu" "F.Mask" "F.Paste")
			(net "SW_SSD4_R")
			(options
				(clearance outline)
				(anchor circle)
			)
			(primitives
				(gr_poly
					(pts
						(arc
							(start -0.1778 -0.2794)
							(mid -0.249642 -0.249642)
							(end -0.2794 -0.1778)
						)
						(arc
							(start -0.2794 0.1778)
							(mid -0.249642 0.249642)
							(end -0.1778 0.2794)
						)
						(arc
							(start 0.1778 0.2794)
							(mid 0.249642 0.249642)
							(end 0.2794 0.1778)
						)
						(arc
							(start 0.2794 -0.1778)
							(mid 0.249642 -0.249642)
							(end 0.1778 -0.2794)
						)
					)
					(width 0)
					(fill yes)
				)
			)
		)
	)
)
